(kicad_pcb
	(version 20221018)
	(generator pcbnew)
	(general
    (thickness 1.7403)
  )
	(paper "A4")
	(title_block
    (title "Data Center RDIMM DDR4 Tester")
    (date "2024-09-30")
    (rev "1.2.4")
		(comment 9 "footprints 250-258 of 690")
	)
	(layers
    (0 "F.Cu" signal)
    (1 "In1.Cu" power)
    (2 "In2.Cu" signal)
    (3 "In3.Cu" power)
    (4 "In4.Cu" power)
    (5 "In5.Cu" signal)
    (6 "In6.Cu" power)
    (7 "In7.Cu" signal)
    (8 "In8.Cu" power)
    (9 "In9.Cu" signal)
    (10 "In10.Cu" power)
    (31 "B.Cu" signal)
    (32 "B.Adhes" user "B.Adhesive")
    (33 "F.Adhes" user "F.Adhesive")
    (34 "B.Paste" user)
    (35 "F.Paste" user)
    (36 "B.SilkS" user "B.Silkscreen")
    (37 "F.SilkS" user "F.Silkscreen")
    (38 "B.Mask" user)
    (39 "F.Mask" user)
    (40 "Dwgs.User" user "User.Drawings")
    (41 "Cmts.User" user "User.Comments")
    (42 "Eco1.User" user "User.Eco1")
    (43 "Eco2.User" user "User.Eco2")
    (44 "Edge.Cuts" user)
    (45 "Margin" user)
    (46 "B.CrtYd" user "B.Courtyard")
    (47 "F.CrtYd" user "F.Courtyard")
    (48 "B.Fab" user)
    (49 "F.Fab" user)
  )
	(footprint "data-center-rdimm-ddr4-tester-footprints:C_0402_1005Metric" (layer "F.Cu")
    (at 254.175 119.86)
    (descr "Capacitor SMD 0402")
    (tags "capacitor SMD 0402")
    (property "Author" "Antmicro")
    (property "Dielectric" "X5R")
    (property "License" "Apache-2.0")
    (property "MPN" "GRM155R61H104KE14D")
    (property "Manufacturer" "Murata")
    (property "Sheetfile" "fmc_hpc.kicad_sch")
    (property "Sheetname" "FMC HPC")
    (property "Val" "100n")
    (property "Voltage" "50V")
    (property "ki_description" " ")
    (attr smd)
    (fp_text reference "C259" (at -1.315 -1.58) (layer "F.SilkS")
        (effects (font (size 0.7 0.7) (thickness 0.15)) (justify left bottom))
    )
    (fp_text value "C_100n_0402" (at 0 1.4) (layer "F.Fab") hide
        (effects (font (size 0.7 0.7) (thickness 0.15)) (justify left bottom))
    )
    (fp_text user "Author: Antmicro" (at -0.932 4.17) (layer "F.Fab") hide
        (effects (font (size 0.7 0.7) (thickness 0.15)) (justify left bottom))
    )
    (fp_text user "License: Apache-2.0" (at -0.932 5.17) (layer "F.Fab") hide
        (effects (font (size 0.7 0.7) (thickness 0.15)) (justify left bottom))
    )
    (fp_text user "${REFERENCE}" (at -0.932 3.168) (layer "F.Fab") hide
        (effects (font (size 0.7 0.7) (thickness 0.15)) (justify left bottom))
    )
    (fp_rect (start -0.94 -0.47) (end 0.94 0.47)
      (stroke (width 0.05) (type solid)) (fill none) (layer "F.CrtYd"))
    (fp_rect (start -0.499 -0.249) (end 0.499 0.249)
      (stroke (width 0.15) (type solid)) (fill none) (layer "F.Fab"))
    (pad "1" smd roundrect (at -0.484 0) (size 0.59 0.64) (layers "F.Cu" "F.Paste" "F.Mask") (roundrect_rratio 0.25)
      (net 410 "/FMC HPC/GTX_TX0_C_P") (pintype "passive"))
    (pad "2" smd roundrect (at 0.484 0) (size 0.59 0.64) (layers "F.Cu" "F.Paste" "F.Mask") (roundrect_rratio 0.25)
      (net 411 "GTX_TX0_P") (pintype "passive"))
  )
	(footprint "data-center-rdimm-ddr4-tester-footprints:Mech_Lightpipe_Mentor_1296.2013" (layer "F.Cu")
    (at 243.15 128.84 180)
    (property "Author" "Antmicro")
    (property "License" "Apache-2.0")
    (property "MPN" "1296.2013")
    (property "Manufacturer" "MENTOR")
    (property "Sheetfile" "data-center-rdimm-ddr4-tester.kicad_sch")
    (property "Sheetname" "")
    (property "ki_description" "PCB Mounted 3-Way Right Angle LED Light Pipe, Tri-Level-Row Clear Dome Lens")
    (attr through_hole)
    (fp_text reference "M1" (at -1.53 -6.22 unlocked) (layer "F.SilkS")
        (effects (font (size 0.7 0.7) (thickness 0.15)) (justify left bottom))
    )
    (fp_text value "Mech_Lightpipe_Mentor_1296.2013" (at -1.75 6.25 180 unlocked) (layer "F.Fab") hide
        (effects (font (size 0.7 0.7) (thickness 0.15)) (justify left bottom))
    )
    (fp_text user "${REFERENCE}" (at -1.75 7.5 180) (layer "F.Fab") hide
        (effects (font (size 0.7 0.7) (thickness 0.15)) (justify left bottom))
    )
    (fp_text user "License: Apache-2.0" (at -1.75 10.25 180) (layer "F.Fab") hide
        (effects (font (size 0.7 0.7) (thickness 0.15)) (justify left bottom))
    )
    (fp_text user "Author: Antmicro" (at -1.75 8.75 180) (layer "F.Fab") hide
        (effects (font (size 0.7 0.7) (thickness 0.15)) (justify left bottom))
    )
    (fp_rect (start -1.508 -6.335) (end 1.507 5.289)
      (stroke (width 0.15) (type solid)) (fill none) (layer "F.SilkS"))
    (pad "" np_thru_hole circle (at 0 -4.96 180) (size 1.2 1.2) (drill 1.2) (layers "F&B.Cu" "*.Mask"))
    (pad "" np_thru_hole circle (at 0 4.24 180) (size 1.2 1.2) (drill 1.2) (layers "F&B.Cu" "*.Mask"))
  )
	(footprint "data-center-rdimm-ddr4-tester-footprints:R_0201" (layer "F.Cu")
    (at 157.06 104.29 -90)
    (descr "Resistor SMD 0201")
    (tags "resistor SMD 0201")
    (property "Author" "Antmicro")
    (property "License" "Apache-2.0")
    (property "MPN" "CR0201-FX-0R00GLF")
    (property "Manufacturer" "Bourns")
    (property "Sheetfile" "ethernet.kicad_sch")
    (property "Sheetname" "Ethernet")
    (property "Tolerance" "1%")
    (property "Val" "0R")
    (property "ki_description" "0R resistor in 0201 package with 1% tolerance")
    (attr smd)
    (fp_text reference "R99" (at -0.65 -0.31 -90) (layer "F.SilkS")
        (effects (font (size 0.7 0.7) (thickness 0.15)) (justify left bottom))
    )
    (fp_text value "R_0R_0201" (at 0 1.25 -90) (layer "F.Fab") hide
        (effects (font (size 0.7 0.7) (thickness 0.15)) (justify left bottom))
    )
    (fp_text user "Author: Antmicro" (at -0.71 5.25 -90) (layer "F.Fab") hide
        (effects (font (size 0.7 0.7) (thickness 0.15)) (justify left bottom))
    )
    (fp_text user "License: Apache-2.0" (at -0.71 4.25 -90) (layer "F.Fab") hide
        (effects (font (size 0.7 0.7) (thickness 0.15)) (justify left bottom))
    )
    (fp_text user "${REFERENCE}" (at -0.71 3.25 -90) (layer "F.Fab") hide
        (effects (font (size 0.7 0.7) (thickness 0.15)) (justify left bottom))
    )
    (fp_rect (start -0.71 -0.36) (end 0.71 0.36)
      (stroke (width 0.05) (type solid)) (fill none) (layer "F.CrtYd"))
    (fp_rect (start -0.3 -0.15) (end 0.298 0.148)
      (stroke (width 0.15) (type solid)) (fill none) (layer "F.Fab"))
    (pad "" smd roundrect (at -0.346 0 270) (size 0.318 0.36) (layers "F.Paste") (roundrect_rratio 0.25))
    (pad "" smd roundrect (at 0.344 0 270) (size 0.318 0.36) (layers "F.Paste") (roundrect_rratio 0.25))
    (pad "1" smd roundrect (at -0.32 0 270) (size 0.46 0.4) (layers "F.Cu" "F.Mask") (roundrect_rratio 0.25)
      (net 169 "/Ethernet/ETH2_P") (pintype "passive"))
    (pad "2" smd roundrect (at 0.32 0 270) (size 0.46 0.4) (layers "F.Cu" "F.Mask") (roundrect_rratio 0.25)
      (net 826 "/Ethernet/ETH2_BP_P") (pintype "passive"))
  )
	(footprint "data-center-rdimm-ddr4-tester-footprints:C_0402_1005Metric" (layer "F.Cu")
    (at 242.3 118.4 -90)
    (descr "Capacitor SMD 0402")
    (tags "capacitor SMD 0402")
    (property "Author" "Antmicro")
    (property "Dielectric" "X5R")
    (property "License" "Apache-2.0")
    (property "MPN" "GRM155R61H104KE14D")
    (property "Manufacturer" "Murata")
    (property "Sheetfile" "pcie.kicad_sch")
    (property "Sheetname" "FPGA banks 115-116")
    (property "Val" "100n")
    (property "Voltage" "50V")
    (property "ki_description" " ")
    (attr smd)
    (fp_text reference "C315" (at -0.84 -0.43 -90) (layer "F.SilkS")
        (effects (font (size 0.7 0.7) (thickness 0.15)) (justify left bottom))
    )
    (fp_text value "C_100n_0402" (at 0 1.4 -90) (layer "F.Fab") hide
        (effects (font (size 0.7 0.7) (thickness 0.15)) (justify left bottom))
    )
    (fp_text user "Author: Antmicro" (at -0.932 4.17 -90) (layer "F.Fab") hide
        (effects (font (size 0.7 0.7) (thickness 0.15)) (justify left bottom))
    )
    (fp_text user "License: Apache-2.0" (at -0.932 5.17 -90) (layer "F.Fab") hide
        (effects (font (size 0.7 0.7) (thickness 0.15)) (justify left bottom))
    )
    (fp_text user "${REFERENCE}" (at -0.932 3.168 -90) (layer "F.Fab") hide
        (effects (font (size 0.7 0.7) (thickness 0.15)) (justify left bottom))
    )
    (fp_rect (start -0.94 -0.47) (end 0.94 0.47)
      (stroke (width 0.05) (type solid)) (fill none) (layer "F.CrtYd"))
    (fp_rect (start -0.499 -0.249) (end 0.499 0.249)
      (stroke (width 0.15) (type solid)) (fill none) (layer "F.Fab"))
    (pad "1" smd roundrect (at -0.484 0 270) (size 0.59 0.64) (layers "F.Cu" "F.Paste" "F.Mask") (roundrect_rratio 0.25)
      (net 885 "/FPGA banks 115-116/GTR_REFCLK2_P") (pintype "passive"))
    (pad "2" smd roundrect (at 0.484 0 270) (size 0.59 0.64) (layers "F.Cu" "F.Paste" "F.Mask") (roundrect_rratio 0.25)
      (net 893 "GTR_REFCLK2_C_P") (pintype "passive"))
  )
	(footprint "data-center-rdimm-ddr4-tester-footprints:C_0402_1005Metric" (layer "F.Cu")
    (at 243.3 118.4 -90)
    (descr "Capacitor SMD 0402")
    (tags "capacitor SMD 0402")
    (property "Author" "Antmicro")
    (property "Dielectric" "X5R")
    (property "License" "Apache-2.0")
    (property "MPN" "GRM155R61H104KE14D")
    (property "Manufacturer" "Murata")
    (property "Sheetfile" "pcie.kicad_sch")
    (property "Sheetname" "FPGA banks 115-116")
    (property "Val" "100n")
    (property "Voltage" "50V")
    (property "ki_description" " ")
    (attr smd)
    (fp_text reference "C316" (at -0.84 -0.4 -90) (layer "F.SilkS")
        (effects (font (size 0.7 0.7) (thickness 0.15)) (justify left bottom))
    )
    (fp_text value "C_100n_0402" (at 0 1.4 -90) (layer "F.Fab") hide
        (effects (font (size 0.7 0.7) (thickness 0.15)) (justify left bottom))
    )
    (fp_text user "${REFERENCE}" (at -0.932 3.168 -90) (layer "F.Fab") hide
        (effects (font (size 0.7 0.7) (thickness 0.15)) (justify left bottom))
    )
    (fp_text user "License: Apache-2.0" (at -0.932 5.17 -90) (layer "F.Fab") hide
        (effects (font (size 0.7 0.7) (thickness 0.15)) (justify left bottom))
    )
    (fp_text user "Author: Antmicro" (at -0.932 4.17 -90) (layer "F.Fab") hide
        (effects (font (size 0.7 0.7) (thickness 0.15)) (justify left bottom))
    )
    (fp_rect (start -0.94 -0.47) (end 0.94 0.47)
      (stroke (width 0.05) (type solid)) (fill none) (layer "F.CrtYd"))
    (fp_rect (start -0.499 -0.249) (end 0.499 0.249)
      (stroke (width 0.15) (type solid)) (fill none) (layer "F.Fab"))
    (pad "1" smd roundrect (at -0.484 0 270) (size 0.59 0.64) (layers "F.Cu" "F.Paste" "F.Mask") (roundrect_rratio 0.25)
      (net 886 "/FPGA banks 115-116/GTR_REFCLK2_N") (pintype "passive"))
    (pad "2" smd roundrect (at 0.484 0 270) (size 0.59 0.64) (layers "F.Cu" "F.Paste" "F.Mask") (roundrect_rratio 0.25)
      (net 894 "GTR_REFCLK2_C_N") (pintype "passive"))
  )
	(footprint "data-center-rdimm-ddr4-tester-footprints:C_0402_1005Metric" (layer "F.Cu")
    (at 153.1 110.615 -90)
    (descr "Capacitor SMD 0402")
    (tags "capacitor SMD 0402")
    (property "Author" "Antmicro")
    (property "DNP" "DNP")
    (property "Dielectric" "")
    (property "License" "Apache-2.0")
    (property "MPN" "GRM155R61A475MEAAD")
    (property "Manufacturer" "Murata")
    (property "Sheetfile" "ethernet.kicad_sch")
    (property "Sheetname" "Ethernet")
    (property "Val" "4u7")
    (property "Voltage" "")
    (property "dnp" "")
    (property "exclude_from_bom" "")
    (property "ki_description" " ")
    (attr exclude_from_pos_files exclude_from_bom)
    (fp_text reference "C230" (at 1.425 0.53 -90) (layer "F.SilkS")
        (effects (font (size 0.7 0.7) (thickness 0.15)) (justify left bottom))
    )
    (fp_text value "C_4u7_0402" (at 0 1.4 -90) (layer "F.Fab") hide
        (effects (font (size 0.7 0.7) (thickness 0.15)) (justify left bottom))
    )
    (fp_text user "License: Apache-2.0" (at -0.932 5.17 -90) (layer "F.Fab") hide
        (effects (font (size 0.7 0.7) (thickness 0.15)) (justify left bottom))
    )
    (fp_text user "Author: Antmicro" (at -0.932 4.17 -90) (layer "F.Fab") hide
        (effects (font (size 0.7 0.7) (thickness 0.15)) (justify left bottom))
    )
    (fp_text user "${REFERENCE}" (at -0.932 3.168 -90) (layer "F.Fab") hide
        (effects (font (size 0.7 0.7) (thickness 0.15)) (justify left bottom))
    )
    (fp_rect (start -0.94 -0.47) (end 0.94 0.47)
      (stroke (width 0.05) (type solid)) (fill none) (layer "F.CrtYd"))
    (fp_rect (start -0.499 -0.249) (end 0.499 0.249)
      (stroke (width 0.15) (type solid)) (fill none) (layer "F.Fab"))
    (pad "1" smd roundrect (at -0.484 0 270) (size 0.59 0.64) (layers "F.Cu" "F.Paste" "F.Mask") (roundrect_rratio 0.25)
      (net 143 "3V3_SYS") (pintype "passive"))
    (pad "2" smd roundrect (at 0.484 0 270) (size 0.59 0.64) (layers "F.Cu" "F.Paste" "F.Mask") (roundrect_rratio 0.25)
      (net 9 "GND") (pintype "passive"))
  )
	(footprint "data-center-rdimm-ddr4-tester-footprints:R_0402_1005Metric" (layer "F.Cu")
    (at 244.772901 119.82 180)
    (descr "Resistor SMD 0402")
    (tags "resistor SMD 0402")
    (property "Author" "Antmicro")
    (property "License" "Apache-2.0")
    (property "MPN" "CR0402-FX-33R0GLF")
    (property "Manufacturer" "Bourns")
    (property "Sheetfile" "fmc_hpc.kicad_sch")
    (property "Sheetname" "FMC HPC")
    (property "Tolerance" "1%")
    (property "Val" "33R")
    (property "ki_description" "33R resistor in 0402 package with 1% tolerance")
    (attr smd)
    (fp_text reference "R151" (at 0.57 1.46 180) (layer "F.SilkS")
        (effects (font (size 0.7 0.7) (thickness 0.15)) (justify left bottom))
    )
    (fp_text value "R_33R_0402" (at 0 1.4 180) (layer "F.Fab") hide
        (effects (font (size 0.7 0.7) (thickness 0.15)) (justify left bottom))
    )
    (fp_text user "${REFERENCE}" (at -0.95 3.168 180) (layer "F.Fab") hide
        (effects (font (size 0.7 0.7) (thickness 0.15)) (justify left bottom))
    )
    (fp_text user "License: Apache-2.0" (at -0.95 5.169 180) (layer "F.Fab") hide
        (effects (font (size 0.7 0.7) (thickness 0.15)) (justify left bottom))
    )
    (fp_text user "Author: Antmicro" (at -0.95 4.169 180) (layer "F.Fab") hide
        (effects (font (size 0.7 0.7) (thickness 0.15)) (justify left bottom))
    )
    (fp_rect (start -0.93 -0.47) (end 0.93 0.47)
      (stroke (width 0.05) (type solid)) (fill none) (layer "F.CrtYd"))
    (fp_rect (start -0.5 -0.25) (end 0.5 0.25)
      (stroke (width 0.15) (type solid)) (fill none) (layer "F.Fab"))
    (pad "1" smd roundrect (at -0.485 0 180) (size 0.59 0.64) (layers "F.Cu" "F.Paste" "F.Mask") (roundrect_rratio 0.25)
      (net 904 "/FMC HPC/GTR_REFCLK2_R_N") (pintype "passive"))
    (pad "2" smd roundrect (at 0.485 0 180) (size 0.59 0.64) (layers "F.Cu" "F.Paste" "F.Mask") (roundrect_rratio 0.25)
      (net 894 "GTR_REFCLK2_C_N") (pintype "passive"))
  )
	(footprint "data-center-rdimm-ddr4-tester-footprints:R_1206_3216Metric" (layer "F.Cu")
    (at 119.65 83.5 90)
    (property "Author" "Antmicro")
    (property "License" "Apache-2.0")
    (property "MPN" "CR1206-J/-000ELF")
    (property "Manufacturer" "Bourns")
    (property "Sheetfile" "supply.kicad_sch")
    (property "Sheetname" "Supply")
    (property "Tolerance" "1%")
    (property "Val" "0R005")
    (property "ki_description" "0R005 resistor in 1206 package with 1% tolerance")
    (attr smd)
    (fp_text reference "R199" (at -1.26 -1.14 90) (layer "F.SilkS")
        (effects (font (size 0.7 0.7) (thickness 0.15)) (justify left bottom))
    )
    (fp_text value "R_0R005_1206" (at 0 2 90) (layer "F.Fab") hide
        (effects (font (size 0.7 0.7) (thickness 0.15)) (justify left bottom))
    )
    (fp_text user "${REFERENCE}" (at -2.401 3.5 90) (layer "F.Fab") hide
        (effects (font (size 0.7 0.7) (thickness 0.15)) (justify left bottom))
    )
    (fp_text user "License: Apache-2.0" (at -2.401 6.3 90) (layer "F.Fab") hide
        (effects (font (size 0.7 0.7) (thickness 0.15)) (justify left bottom))
    )
    (fp_text user "Author: Antmicro" (at -2.401 4.899 90) (layer "F.Fab") hide
        (effects (font (size 0.7 0.7) (thickness 0.15)) (justify left bottom))
    )
    (fp_line (start 0 -0.902) (end -0.5 -0.902)
      (stroke (width 0.15) (type solid)) (layer "F.SilkS"))
    (fp_line (start 0 -0.902) (end 0.498 -0.902)
      (stroke (width 0.15) (type solid)) (layer "F.SilkS"))
    (fp_line (start 0 0.9) (end -0.5 0.9)
      (stroke (width 0.15) (type solid)) (layer "F.SilkS"))
    (fp_line (start 0 0.9) (end 0.498 0.9)
      (stroke (width 0.15) (type solid)) (layer "F.SilkS"))
    (fp_rect (start -2.25 -1.05) (end 2.25 1.05)
      (stroke (width 0.05) (type solid)) (fill none) (layer "F.CrtYd"))
    (fp_line (start -1.601 -0.802) (end -1.601 0.8)
      (stroke (width 0.15) (type solid)) (layer "F.Fab"))
    (fp_line (start -1.601 -0.802) (end 1.6 -0.802)
      (stroke (width 0.15) (type solid)) (layer "F.Fab"))
    (fp_line (start -1.601 0.8) (end 1.6 0.8)
      (stroke (width 0.15) (type solid)) (layer "F.Fab"))
    (fp_line (start 1.6 -0.802) (end 1.6 0.8)
      (stroke (width 0.15) (type solid)) (layer "F.Fab"))
    (pad "1" smd roundrect (at -1.5 0 90) (size 1.2 1.8) (layers "F.Cu" "F.Paste" "F.Mask") (roundrect_rratio 0.15)
      (net 301 "VDD1V2") (pintype "passive"))
    (pad "2" smd roundrect (at 1.499 0 90) (size 1.2 1.8) (layers "F.Cu" "F.Paste" "F.Mask") (roundrect_rratio 0.15)
      (net 77 "VDDQ") (pintype "passive"))
  )
	(footprint "data-center-rdimm-ddr4-tester-footprints:LED_0603_1608Metric_G" (layer "F.Cu")
    (at 202.8 111.9)
    (descr "LED SMD 0603 Green")
    (tags "LED SMD 0603 Green")
    (property "Author" "Antmicro")
    (property "License" "Apache-2.0")
    (property "MPN" "KP-1608CGCK")
    (property "Manufacturer" "Kingbright")
    (property "Sheetfile" "ethernet.kicad_sch")
    (property "Sheetname" "Ethernet")
    (attr smd)
    (fp_text reference "D15" (at -1 -0.72) (layer "F.SilkS")
        (effects (font (size 0.7 0.7) (thickness 0.15)) (justify left bottom))
    )
    (fp_text value "LED_G_0603_KP-1608CGCK" (at 0 1.6) (layer "F.Fab") hide
        (effects (font (size 0.7 0.7) (thickness 0.15)) (justify left bottom))
    )
    (fp_text user "Author: Antmicro" (at -1.31 4.769) (layer "F.Fab") hide
        (effects (font (size 0.7 0.7) (thickness 0.15)) (justify left bottom))
    )
    (fp_text user "${REFERENCE}" (at -1.31 3.769) (layer "F.Fab") hide
        (effects (font (size 0.7 0.7) (thickness 0.15)) (justify left bottom))
    )
    (fp_text user "License: Apache-2.0" (at -1.31 5.769) (layer "F.Fab") hide
        (effects (font (size 0.7 0.7) (thickness 0.15)) (justify left bottom))
    )
    (fp_line (start -0.27 -0.35) (end 0.27 -0.35)
      (stroke (width 0.15) (type solid)) (layer "F.SilkS"))
    (fp_line (start -0.27 0.351) (end 0.27 0.351)
      (stroke (width 0.15) (type solid)) (layer "F.SilkS"))
    (fp_line (start -0.106328 -0.200008) (end -0.106328 0.199992)
      (stroke (width 0.1) (type solid)) (layer "F.SilkS"))
    (fp_line (start -0.106328 -0.200008) (end 0.093672 -0.000008)
      (stroke (width 0.1) (type solid)) (layer "F.SilkS"))
    (fp_line (start -0.106328 -0.000008) (end -0.29 0)
      (stroke (width 0.1) (type solid)) (layer "F.SilkS"))
    (fp_line (start 0.093672 -0.200008) (end 0.093672 0.199992)
      (stroke (width 0.1) (type solid)) (layer "F.SilkS"))
    (fp_line (start 0.093672 -0.000008) (end -0.106328 0.199992)
      (stroke (width 0.1) (type solid)) (layer "F.SilkS"))
    (fp_line (start 0.093672 -0.000008) (end 0.293672 -0.000008)
      (stroke (width 0.1) (type solid)) (layer "F.SilkS"))
    (fp_line (start 1.25 0.32) (end 1.25 -0.32)
      (stroke (width 0.15) (type solid)) (layer "F.SilkS"))
    (fp_rect (start 1.26 0.65) (end -1.26 -0.65)
      (stroke (width 0.05) (type solid)) (fill none) (layer "F.CrtYd"))
    (fp_line (start -0.599 0) (end -0.201 0)
      (stroke (width 0.15) (type solid)) (layer "F.Fab"))
    (fp_line (start -0.201 -0.2) (end -0.201 0)
      (stroke (width 0.15) (type solid)) (layer "F.Fab"))
    (fp_line (start -0.201 0) (end -0.201 0.202)
      (stroke (width 0.15) (type solid)) (layer "F.Fab"))
    (fp_line (start -0.201 0.202) (end 0.101 0)
      (stroke (width 0.15) (type solid)) (layer "F.Fab"))
    (fp_line (start 0.101 0) (end -0.201 -0.2)
      (stroke (width 0.15) (type solid)) (layer "F.Fab"))
    (fp_line (start 0.199 -0.2) (end 0.199 -0.1)
      (stroke (width 0.15) (type solid)) (layer "F.Fab"))
    (fp_line (start 0.199 0) (end 0.597 0)
      (stroke (width 0.15) (type solid)) (layer "F.Fab"))
    (fp_line (start 0.199 0.202) (end 0.199 -0.1)
      (stroke (width 0.15) (type solid)) (layer "F.Fab"))
    (fp_rect (start -0.848 -0.4) (end 0.85 0.402)
      (stroke (width 0.15) (type solid)) (fill none) (layer "F.Fab"))
    (pad "1" smd rect (at -0.75 0 180) (size 0.8 0.8) (layers "F.Cu" "F.Paste" "F.Mask")
      (net 609 "Net-(D15-Pad1)") (pinfunction "1") (pintype "passive"))
    (pad "2" smd rect (at 0.75 0 180) (size 0.8 0.8) (layers "F.Cu" "F.Paste" "F.Mask")
      (net 604 "GNDD") (pinfunction "2") (pintype "passive"))
  )
)
